(kicad_pcb
	(version 20260206)
	(generator "pcbnew")
	(generator_version "10.0")
	(general
		(thickness 1.6)
		(legacy_teardrops no)
	)
	(paper "A4")
	(title_block
		(title "dpb — 14545-sa.0730WZS0815.brd")
		(comment 1 "Honey Badger (Wiwynn) / footprint 511 of 1066 (CN2), pads 94-166 of 166")
	)
	(layers
		(0 "F.Cu" signal "TOP")
		(4 "In1.Cu" signal "L2GND")
		(6 "In2.Cu" signal "L3")
		(8 "In3.Cu" signal "L4VCC")
		(10 "In4.Cu" signal "L5VCC")
		(12 "In5.Cu" signal "L6")
		(14 "In6.Cu" signal "L7GND")
		(2 "B.Cu" signal "BOTTOM")
		(9 "F.Adhes" user "F.Adhesive")
		(11 "B.Adhes" user "B.Adhesive")
		(13 "F.Paste" user "Package Geometry/Pastemask Top")
		(15 "B.Paste" user "Package Geometry/Pastemask Bottom")
		(5 "F.SilkS" user "Ref Des/Silkscreen Top")
		(7 "B.SilkS" user "Ref Des/Silkscreen Bottom")
		(1 "F.Mask" user "Board Geometry/Soldermask Top")
		(3 "B.Mask" user "Board Geometry/Soldermask Bottom")
		(17 "Dwgs.User" user "User.Drawings")
		(19 "Cmts.User" user "User.Comments")
		(21 "Eco1.User" user "User.Eco1")
		(23 "Eco2.User" user "User.Eco2")
		(25 "Edge.Cuts" user "Board Geometry/Outline")
		(27 "Margin" user)
		(31 "F.CrtYd" user "Package Geometry/Place Bound Top")
		(29 "B.CrtYd" user "Package Geometry/Place Bound Bottom")
		(35 "F.Fab" user "Ref Des/Assembly Top")
		(33 "B.Fab" user "Ref Des/Assembly Bottom")
	)
	(footprint ""
		(layer "F.Cu")
		(at 2.500122 -105.998518 -90)
		(property "Reference" "CN2"
			(at 0 0 270)
			(layer "F.SilkS")
			(hide yes)
			(effects
				(font
					(size 1.27 1.27)
				)
			)
		)
		(property "Value" "PCISLT164-70-GP"
			(at -77.8764 -6.4262 270)
			(unlocked yes)
			(layer "F.Fab")
			(hide yes)
			(effects
				(font
					(size 1.016 1.016)
					(thickness 0.1524)
				)
			)
		)
		(property "Device Type" "G630EAA12048EU"
			(at -77.8764 -7.9502 270)
			(unlocked yes)
			(layer "F.Fab")
			(hide yes)
			(effects
				(font
					(size 1.016 1.016)
					(thickness 0.1524)
				)
			)
		)
		(duplicate_pad_numbers_are_jumpers no)
		(pad "B10" smd rect
			(at 2.500122 -0.692404 270)
			(size 0.7112 3.6068)
			(layers "F.Cu" "F.Mask" "F.Paste")
			(net "GND")
		)
		(pad "B11" smd rect
			(at 1.500124 -0.692404 270)
			(size 0.7112 3.6068)
			(layers "F.Cu" "F.Mask" "F.Paste")
			(net "DPB_HW_REV")
		)
		(pad "B12" smd rect
			(at -1.500124 -0.692404 270)
			(size 0.7112 3.6068)
			(layers "F.Cu" "F.Mask" "F.Paste")
			(net "SAS2X28_B_HDD9_TX_+")
		)
		(pad "B13" smd rect
			(at -2.500376 -0.692404 270)
			(size 0.7112 3.6068)
			(layers "F.Cu" "F.Mask" "F.Paste")
			(net "SAS2X28_B_HDD9_TX_-")
		)
		(pad "B14" smd rect
			(at -3.500374 -0.692404 270)
			(size 0.7112 3.6068)
			(layers "F.Cu" "F.Mask" "F.Paste")
			(net "GND")
		)
		(pad "B15" smd rect
			(at -4.500372 -0.692404 270)
			(size 0.7112 3.6068)
			(layers "F.Cu" "F.Mask" "F.Paste")
			(net "GND")
		)
		(pad "B16" smd rect
			(at -5.50037 -0.692404 270)
			(size 0.7112 3.6068)
			(layers "F.Cu" "F.Mask" "F.Paste")
			(net "SAS2X28_B_HDD3_TX_+")
		)
		(pad "B17" smd rect
			(at -6.500368 -0.692404 270)
			(size 0.7112 3.6068)
			(layers "F.Cu" "F.Mask" "F.Paste")
			(net "SAS2X28_B_HDD3_TX_-")
		)
		(pad "B18" smd rect
			(at -7.500366 -0.692404 270)
			(size 0.7112 3.6068)
			(layers "F.Cu" "F.Mask" "F.Paste")
			(net "GND")
		)
		(pad "B19" smd rect
			(at -8.500364 -0.692404 270)
			(size 0.7112 3.6068)
			(layers "F.Cu" "F.Mask" "F.Paste")
			(net "GND")
		)
		(pad "B20" smd rect
			(at -9.500362 -0.692404 270)
			(size 0.7112 3.6068)
			(layers "F.Cu" "F.Mask" "F.Paste")
			(net "SAS2X28_B_HDD2_TX_+")
		)
		(pad "B21" smd rect
			(at -10.50036 -0.692404 270)
			(size 0.7112 3.6068)
			(layers "F.Cu" "F.Mask" "F.Paste")
			(net "SAS2X28_B_HDD2_TX_-")
		)
		(pad "B22" smd rect
			(at -11.500358 -0.692404 270)
			(size 0.7112 3.6068)
			(layers "F.Cu" "F.Mask" "F.Paste")
			(net "GND")
		)
		(pad "B23" smd rect
			(at -12.500356 -0.692404 270)
			(size 0.7112 3.6068)
			(layers "F.Cu" "F.Mask" "F.Paste")
			(net "GND")
		)
		(pad "B24" smd rect
			(at -13.500354 -0.692404 270)
			(size 0.7112 3.6068)
			(layers "F.Cu" "F.Mask" "F.Paste")
			(net "SAS2X28_B_HDD8_TX_+")
		)
		(pad "B25" smd rect
			(at -14.500352 -0.692404 270)
			(size 0.7112 3.6068)
			(layers "F.Cu" "F.Mask" "F.Paste")
			(net "SAS2X28_B_HDD8_TX_-")
		)
		(pad "B26" smd rect
			(at -15.50035 -0.692404 270)
			(size 0.7112 3.6068)
			(layers "F.Cu" "F.Mask" "F.Paste")
			(net "GND")
		)
		(pad "B27" smd rect
			(at -16.500348 -0.692404 270)
			(size 0.7112 3.6068)
			(layers "F.Cu" "F.Mask" "F.Paste")
			(net "GND")
		)
		(pad "B28" smd rect
			(at -17.500346 -0.692404 270)
			(size 0.7112 3.6068)
			(layers "F.Cu" "F.Mask" "F.Paste")
			(net "SAS2X28_B_HDD7_TX_+")
		)
		(pad "B29" smd rect
			(at -18.500344 -0.692404 270)
			(size 0.7112 3.6068)
			(layers "F.Cu" "F.Mask" "F.Paste")
			(net "SAS2X28_B_HDD7_TX_-")
		)
		(pad "B30" smd rect
			(at -19.500342 -0.692404 270)
			(size 0.7112 3.6068)
			(layers "F.Cu" "F.Mask" "F.Paste")
			(net "GND")
		)
		(pad "B31" smd rect
			(at -20.50034 -0.692404 270)
			(size 0.7112 3.6068)
			(layers "F.Cu" "F.Mask" "F.Paste")
			(net "GND")
		)
		(pad "B32" smd rect
			(at -21.500338 -0.692404 270)
			(size 0.7112 3.6068)
			(layers "F.Cu" "F.Mask" "F.Paste")
			(net "SAS2X28_B_HDD1_TX_+")
		)
		(pad "B33" smd rect
			(at -22.500336 -0.692404 270)
			(size 0.7112 3.6068)
			(layers "F.Cu" "F.Mask" "F.Paste")
			(net "SAS2X28_B_HDD1_TX_-")
		)
		(pad "B34" smd rect
			(at -23.500334 -0.692404 270)
			(size 0.7112 3.6068)
			(layers "F.Cu" "F.Mask" "F.Paste")
			(net "GND")
		)
		(pad "B35" smd rect
			(at -24.500332 -0.692404 270)
			(size 0.7112 3.6068)
			(layers "F.Cu" "F.Mask" "F.Paste")
			(net "GND")
		)
		(pad "B36" smd rect
			(at -25.50033 -0.692404 270)
			(size 0.7112 3.6068)
			(layers "F.Cu" "F.Mask" "F.Paste")
			(net "SAS2X28_B_HDD0_TX_+")
		)
		(pad "B37" smd rect
			(at -26.500328 -0.692404 270)
			(size 0.7112 3.6068)
			(layers "F.Cu" "F.Mask" "F.Paste")
			(net "SAS2X28_B_HDD0_TX_-")
		)
		(pad "B38" smd rect
			(at -27.500326 -0.692404 270)
			(size 0.7112 3.6068)
			(layers "F.Cu" "F.Mask" "F.Paste")
			(net "GND")
		)
		(pad "B39" smd rect
			(at -28.500324 -0.692404 270)
			(size 0.7112 3.6068)
			(layers "F.Cu" "F.Mask" "F.Paste")
			(net "GND")
		)
		(pad "B40" smd rect
			(at -29.500322 -0.692404 270)
			(size 0.7112 3.6068)
			(layers "F.Cu" "F.Mask" "F.Paste")
			(net "SAS2X28_B_HDD13_TX_+")
		)
		(pad "B41" smd rect
			(at -30.50032 -0.692404 270)
			(size 0.7112 3.6068)
			(layers "F.Cu" "F.Mask" "F.Paste")
			(net "SAS2X28_B_HDD13_TX_-")
		)
		(pad "B42" smd rect
			(at -31.500318 -0.692404 270)
			(size 0.7112 3.6068)
			(layers "F.Cu" "F.Mask" "F.Paste")
			(net "GND")
		)
		(pad "B43" smd rect
			(at -32.500316 -0.692404 270)
			(size 0.7112 3.6068)
			(layers "F.Cu" "F.Mask" "F.Paste")
			(net "SAS2X28_B_HDD13_FLT")
		)
		(pad "B44" smd rect
			(at -33.500314 -0.692404 270)
			(size 0.7112 3.6068)
			(layers "F.Cu" "F.Mask" "F.Paste")
			(net "SAS2X28_B_HDD6_FLT")
		)
		(pad "B45" smd rect
			(at -34.500312 -0.692404 270)
			(size 0.7112 3.6068)
			(layers "F.Cu" "F.Mask" "F.Paste")
			(net "SAS2X28_B_HDD5_FLT")
		)
		(pad "B46" smd rect
			(at -35.50031 -0.692404 270)
			(size 0.7112 3.6068)
			(layers "F.Cu" "F.Mask" "F.Paste")
			(net "SAS2X28_B_HDD10_FLT")
		)
		(pad "B47" smd rect
			(at -36.500308 -0.692404 270)
			(size 0.7112 3.6068)
			(layers "F.Cu" "F.Mask" "F.Paste")
			(net "SAS2X28_B_HDD11_FLT")
		)
		(pad "B48" smd rect
			(at -37.500306 -0.692404 270)
			(size 0.7112 3.6068)
			(layers "F.Cu" "F.Mask" "F.Paste")
			(net "GND")
		)
		(pad "B49" smd rect
			(at -38.500304 -0.692404 270)
			(size 0.7112 3.6068)
			(layers "F.Cu" "F.Mask" "F.Paste")
			(net "SAS2X28_B_HDD6_TX_+")
		)
		(pad "B50" smd rect
			(at -39.500302 -0.692404 270)
			(size 0.7112 3.6068)
			(layers "F.Cu" "F.Mask" "F.Paste")
			(net "SAS2X28_B_HDD6_TX_-")
		)
		(pad "B51" smd rect
			(at -40.5003 -0.692404 270)
			(size 0.7112 3.6068)
			(layers "F.Cu" "F.Mask" "F.Paste")
			(net "GND")
		)
		(pad "B52" smd rect
			(at -41.500298 -0.692404 270)
			(size 0.7112 3.6068)
			(layers "F.Cu" "F.Mask" "F.Paste")
			(net "SAS2X28_B_HDD12_FLT")
		)
		(pad "B53" smd rect
			(at -42.500296 -0.692404 270)
			(size 0.7112 3.6068)
			(layers "F.Cu" "F.Mask" "F.Paste")
			(net "SAS2X28_B_HDD15_FLT")
		)
		(pad "B54" smd rect
			(at -43.500294 -0.692404 270)
			(size 0.7112 3.6068)
			(layers "F.Cu" "F.Mask" "F.Paste")
			(net "SELF_1B&2B_HB")
		)
		(pad "B55" smd rect
			(at -44.500292 -0.692404 270)
			(size 0.7112 3.6068)
			(layers "F.Cu" "F.Mask" "F.Paste")
			(net "HB_EXP_B_INPUT")
		)
		(pad "B56" smd rect
			(at -45.50029 -0.692404 270)
			(size 0.7112 3.6068)
			(layers "F.Cu" "F.Mask" "F.Paste")
			(net "I2C_B_SCL_DAMP_B")
		)
		(pad "B57" smd rect
			(at -46.500288 -0.692404 270)
			(size 0.7112 3.6068)
			(layers "F.Cu" "F.Mask" "F.Paste")
			(net "I2C_B_SDA_DAMP_B")
		)
		(pad "B58" smd rect
			(at -47.500286 -0.692404 270)
			(size 0.7112 3.6068)
			(layers "F.Cu" "F.Mask" "F.Paste")
			(net "TEMP_SENSOR_B_ADDR0&ID")
		)
		(pad "B59" smd rect
			(at -48.500284 -0.692404 270)
			(size 0.7112 3.6068)
			(layers "F.Cu" "F.Mask" "F.Paste")
			(net "PWM_EXP_B")
		)
		(pad "B60" smd rect
			(at -49.500282 -0.692404 270)
			(size 0.7112 3.6068)
			(layers "F.Cu" "F.Mask" "F.Paste")
			(net "PEER_1A&2A_HB")
		)
		(pad "B61" smd rect
			(at -50.50028 -0.692404 270)
			(size 0.7112 3.6068)
			(layers "F.Cu" "F.Mask" "F.Paste")
			(net "GND")
		)
		(pad "B62" smd rect
			(at -51.500278 -0.692404 270)
			(size 0.7112 3.6068)
			(layers "F.Cu" "F.Mask" "F.Paste")
			(net "SAS2X28_B_HDD5_TX_+")
		)
		(pad "B63" smd rect
			(at -52.500276 -0.692404 270)
			(size 0.7112 3.6068)
			(layers "F.Cu" "F.Mask" "F.Paste")
			(net "SAS2X28_B_HDD5_TX_-")
		)
		(pad "B64" smd rect
			(at -53.500274 -0.692404 270)
			(size 0.7112 3.6068)
			(layers "F.Cu" "F.Mask" "F.Paste")
			(net "GND")
		)
		(pad "B65" smd rect
			(at -54.500272 -0.692404 270)
			(size 0.7112 3.6068)
			(layers "F.Cu" "F.Mask" "F.Paste")
			(net "GND")
		)
		(pad "B66" smd rect
			(at -55.50027 -0.692404 270)
			(size 0.7112 3.6068)
			(layers "F.Cu" "F.Mask" "F.Paste")
			(net "SAS2X28_B_HDD10_TX_+")
		)
		(pad "B67" smd rect
			(at -56.500268 -0.692404 270)
			(size 0.7112 3.6068)
			(layers "F.Cu" "F.Mask" "F.Paste")
			(net "SAS2X28_B_HDD10_TX_-")
		)
		(pad "B68" smd rect
			(at -57.500266 -0.692404 270)
			(size 0.7112 3.6068)
			(layers "F.Cu" "F.Mask" "F.Paste")
			(net "GND")
		)
		(pad "B69" smd rect
			(at -58.500264 -0.692404 270)
			(size 0.7112 3.6068)
			(layers "F.Cu" "F.Mask" "F.Paste")
			(net "GND")
		)
		(pad "B70" smd rect
			(at -59.500262 -0.692404 270)
			(size 0.7112 3.6068)
			(layers "F.Cu" "F.Mask" "F.Paste")
			(net "SAS2X28_B_HDD11_TX_+")
		)
		(pad "B71" smd rect
			(at -60.50026 -0.692404 270)
			(size 0.7112 3.6068)
			(layers "F.Cu" "F.Mask" "F.Paste")
			(net "SAS2X28_B_HDD11_TX_-")
		)
		(pad "B72" smd rect
			(at -61.500258 -0.692404 270)
			(size 0.7112 3.6068)
			(layers "F.Cu" "F.Mask" "F.Paste")
			(net "GND")
		)
		(pad "B73" smd rect
			(at -62.500256 -0.692404 270)
			(size 0.7112 3.6068)
			(layers "F.Cu" "F.Mask" "F.Paste")
			(net "GND")
		)
		(pad "B74" smd rect
			(at -63.500254 -0.692404 270)
			(size 0.7112 3.6068)
			(layers "F.Cu" "F.Mask" "F.Paste")
			(net "SAS2X28_B_HDD12_TX_+")
		)
		(pad "B75" smd rect
			(at -64.500252 -0.692404 270)
			(size 0.7112 3.6068)
			(layers "F.Cu" "F.Mask" "F.Paste")
			(net "SAS2X28_B_HDD12_TX_-")
		)
		(pad "B76" smd rect
			(at -65.50025 -0.692404 270)
			(size 0.7112 3.6068)
			(layers "F.Cu" "F.Mask" "F.Paste")
			(net "GND")
		)
		(pad "B77" smd rect
			(at -66.500248 -0.692404 270)
			(size 0.7112 3.6068)
			(layers "F.Cu" "F.Mask" "F.Paste")
			(net "GND")
		)
		(pad "B78" smd rect
			(at -67.500246 -0.692404 270)
			(size 0.7112 3.6068)
			(layers "F.Cu" "F.Mask" "F.Paste")
			(net "SEB_BA_TX+")
		)
		(pad "B79" smd rect
			(at -68.500244 -0.692404 270)
			(size 0.7112 3.6068)
			(layers "F.Cu" "F.Mask" "F.Paste")
			(net "SEB_BA_TX-")
		)
		(pad "B80" smd rect
			(at -69.500242 -0.692404 270)
			(size 0.7112 3.6068)
			(layers "F.Cu" "F.Mask" "F.Paste")
			(net "GND")
		)
		(pad "B81" smd rect
			(at -70.50024 -0.692404 270)
			(size 0.7112 3.6068)
			(layers "F.Cu" "F.Mask" "F.Paste")
			(net "GND")
		)
		(pad "B82" smd rect
			(at -71.500238 -0.692404 270)
			(size 0.7112 3.6068)
			(layers "F.Cu" "F.Mask" "F.Paste")
			(net "GND")
		)
	)
)
